(kicad_pcb
	(version 20260206)
	(generator "pcbnew")
	(generator_version "10.0")
	(general
		(thickness 1.6)
		(legacy_teardrops no)
	)
	(paper "A4")
	(title_block
		(title "04192023_DAF0TMB3IC0_F0TG_MB_C_brd_V02_OCP.brd")
		(comment 1 "Grand Teton / footprints 3073-3077 of 8354")
	)
	(layers
		(0 "F.Cu" signal "TOP")
		(4 "In1.Cu" signal "GND")
		(6 "In2.Cu" signal "IN1")
		(8 "In3.Cu" signal "GND1")
		(10 "In4.Cu" signal "IN2")
		(12 "In5.Cu" signal "GND2")
		(14 "In6.Cu" signal "IN3")
		(16 "In7.Cu" signal "GND3")
		(18 "In8.Cu" signal "VCC")
		(20 "In9.Cu" signal "VCC1")
		(22 "In10.Cu" signal "GND4")
		(24 "In11.Cu" signal "IN4")
		(26 "In12.Cu" signal "GND5")
		(28 "In13.Cu" signal "IN5")
		(30 "In14.Cu" signal "GND6")
		(32 "In15.Cu" signal "IN6")
		(34 "In16.Cu" signal "GND7")
		(2 "B.Cu" signal "BOTTOM")
		(9 "F.Adhes" user "F.Adhesive")
		(11 "B.Adhes" user "B.Adhesive")
		(13 "F.Paste" user "Package Geometry/Pastemask Top")
		(15 "B.Paste" user "Package Geometry/Pastemask Bottom")
		(5 "F.SilkS" user "Ref Des/Silkscreen Top")
		(7 "B.SilkS" user "Ref Des/Silkscreen Bottom")
		(1 "F.Mask" user "Board Geometry/Soldermask Top")
		(3 "B.Mask" user "Board Geometry/Soldermask Bottom")
		(17 "Dwgs.User" user "User.Drawings")
		(19 "Cmts.User" user "User.Comments")
		(21 "Eco1.User" user "User.Eco1")
		(23 "Eco2.User" user "User.Eco2")
		(25 "Edge.Cuts" user "Board Geometry/Outline")
		(27 "Margin" user)
		(31 "F.CrtYd" user "Package Geometry/Place Bound Top")
		(29 "B.CrtYd" user "Package Geometry/Place Bound Bottom")
		(35 "F.Fab" user "Ref Des/Assembly Top")
		(33 "B.Fab" user "Ref Des/Assembly Bottom")
	)
	(footprint ""
		(layer "F.Cu")
		(at 61.027564 -16.220948 -90)
		(property "Reference" "R3171"
			(at 0 0 270)
			(layer "F.SilkS")
			(hide yes)
			(effects
				(font
					(size 1.27 1.27)
				)
			)
		)
		(property "Value" ""
			(at 0 0 270)
			(layer "F.Fab")
			(effects
				(font
					(size 1.27 1.27)
				)
			)
		)
		(duplicate_pad_numbers_are_jumpers no)
		(fp_line
			(start -0.7874 0.4064)
			(end -0.7874 -0.4064)
			(stroke
				(width 0.1524)
				(type default)
			)
			(layer "F.SilkS")
		)
		(fp_line
			(start 0.7874 0.4064)
			(end -0.7874 0.4064)
			(stroke
				(width 0.1524)
				(type default)
			)
			(layer "F.SilkS")
		)
		(fp_line
			(start -0.7874 -0.4064)
			(end 0.7874 -0.4064)
			(stroke
				(width 0.1524)
				(type default)
			)
			(layer "F.SilkS")
		)
		(fp_line
			(start 0.7874 -0.4064)
			(end 0.7874 0.4064)
			(stroke
				(width 0.1524)
				(type default)
			)
			(layer "F.SilkS")
		)
		(fp_line
			(start -0.67945 0.3048)
			(end -0.67945 -0.305054)
			(stroke
				(width 0.1)
				(type default)
			)
			(layer "F.Fab")
		)
		(fp_line
			(start -0.12065 0.3048)
			(end -0.67945 0.3048)
			(stroke
				(width 0.1)
				(type default)
			)
			(layer "F.Fab")
		)
		(fp_line
			(start 0.120396 0.3048)
			(end 0.120396 0.2794)
			(stroke
				(width 0.1)
				(type default)
			)
			(layer "F.Fab")
		)
		(fp_line
			(start 0.67945 0.3048)
			(end 0.120396 0.3048)
			(stroke
				(width 0.1)
				(type default)
			)
			(layer "F.Fab")
		)
		(fp_line
			(start -0.12065 0.2794)
			(end -0.12065 0.3048)
			(stroke
				(width 0.1)
				(type default)
			)
			(layer "F.Fab")
		)
		(fp_line
			(start 0.120396 0.2794)
			(end -0.12065 0.2794)
			(stroke
				(width 0.1)
				(type default)
			)
			(layer "F.Fab")
		)
		(fp_line
			(start -0.12065 -0.2794)
			(end 0.12065 -0.2794)
			(stroke
				(width 0.1)
				(type default)
			)
			(layer "F.Fab")
		)
		(fp_line
			(start 0.12065 -0.2794)
			(end 0.12065 -0.3048)
			(stroke
				(width 0.1)
				(type default)
			)
			(layer "F.Fab")
		)
		(fp_line
			(start 0.12065 -0.3048)
			(end 0.67945 -0.3048)
			(stroke
				(width 0.1)
				(type default)
			)
			(layer "F.Fab")
		)
		(fp_line
			(start 0.67945 -0.3048)
			(end 0.67945 0.3048)
			(stroke
				(width 0.1)
				(type default)
			)
			(layer "F.Fab")
		)
		(fp_line
			(start -0.67945 -0.305054)
			(end -0.12065 -0.305054)
			(stroke
				(width 0.1)
				(type default)
			)
			(layer "F.Fab")
		)
		(fp_line
			(start -0.12065 -0.305054)
			(end -0.12065 -0.2794)
			(stroke
				(width 0.1)
				(type default)
			)
			(layer "F.Fab")
		)
		(pad "1" smd circle
			(at -0.40005 0 270)
			(size 0 0)
			(layers "F.Cu" "F.Mask" "F.Paste")
			(net "OCP_V3_2_ISO_BIF2_EN")
		)
		(pad "2" smd circle
			(at 0.40005 0 270)
			(size 0 0)
			(layers "F.Cu" "F.Mask" "F.Paste")
			(net "OCP_V3_2_BIF2_R_N")
		)
	)
	(footprint ""
		(layer "F.Cu")
		(at 148.494242 -105.624884 180)
		(property "Reference" "R3298"
			(at 0 0 180)
			(layer "F.SilkS")
			(hide yes)
			(effects
				(font
					(size 1.27 1.27)
				)
			)
		)
		(property "Value" ""
			(at 0 0 180)
			(layer "F.Fab")
			(effects
				(font
					(size 1.27 1.27)
				)
			)
		)
		(duplicate_pad_numbers_are_jumpers no)
		(fp_line
			(start 0.7874 0.4064)
			(end -0.7874 0.4064)
			(stroke
				(width 0.1524)
				(type default)
			)
			(layer "F.SilkS")
		)
		(fp_line
			(start 0.7874 -0.4064)
			(end 0.7874 0.4064)
			(stroke
				(width 0.1524)
				(type default)
			)
			(layer "F.SilkS")
		)
		(fp_line
			(start -0.7874 0.4064)
			(end -0.7874 -0.4064)
			(stroke
				(width 0.1524)
				(type default)
			)
			(layer "F.SilkS")
		)
		(fp_line
			(start -0.7874 -0.4064)
			(end 0.7874 -0.4064)
			(stroke
				(width 0.1524)
				(type default)
			)
			(layer "F.SilkS")
		)
		(fp_line
			(start 0.67945 0.3048)
			(end 0.120396 0.3048)
			(stroke
				(width 0.1)
				(type default)
			)
			(layer "F.Fab")
		)
		(fp_line
			(start 0.67945 -0.3048)
			(end 0.67945 0.3048)
			(stroke
				(width 0.1)
				(type default)
			)
			(layer "F.Fab")
		)
		(fp_line
			(start 0.12065 -0.2794)
			(end 0.12065 -0.3048)
			(stroke
				(width 0.1)
				(type default)
			)
			(layer "F.Fab")
		)
		(fp_line
			(start 0.12065 -0.3048)
			(end 0.67945 -0.3048)
			(stroke
				(width 0.1)
				(type default)
			)
			(layer "F.Fab")
		)
		(fp_line
			(start 0.120396 0.3048)
			(end 0.120396 0.2794)
			(stroke
				(width 0.1)
				(type default)
			)
			(layer "F.Fab")
		)
		(fp_line
			(start 0.120396 0.2794)
			(end -0.12065 0.2794)
			(stroke
				(width 0.1)
				(type default)
			)
			(layer "F.Fab")
		)
		(fp_line
			(start -0.12065 0.3048)
			(end -0.67945 0.3048)
			(stroke
				(width 0.1)
				(type default)
			)
			(layer "F.Fab")
		)
		(fp_line
			(start -0.12065 0.2794)
			(end -0.12065 0.3048)
			(stroke
				(width 0.1)
				(type default)
			)
			(layer "F.Fab")
		)
		(fp_line
			(start -0.12065 -0.2794)
			(end 0.12065 -0.2794)
			(stroke
				(width 0.1)
				(type default)
			)
			(layer "F.Fab")
		)
		(fp_line
			(start -0.12065 -0.305054)
			(end -0.12065 -0.2794)
			(stroke
				(width 0.1)
				(type default)
			)
			(layer "F.Fab")
		)
		(fp_line
			(start -0.67945 0.3048)
			(end -0.67945 -0.305054)
			(stroke
				(width 0.1)
				(type default)
			)
			(layer "F.Fab")
		)
		(fp_line
			(start -0.67945 -0.305054)
			(end -0.12065 -0.305054)
			(stroke
				(width 0.1)
				(type default)
			)
			(layer "F.Fab")
		)
		(pad "1" smd circle
			(at -0.40005 0 180)
			(size 0 0)
			(layers "F.Cu" "F.Mask" "F.Paste")
			(net "P3V3_AUX")
		)
		(pad "2" smd circle
			(at 0.40005 0 180)
			(size 0 0)
			(layers "F.Cu" "F.Mask" "F.Paste")
			(net "HDD_ACTIVITY_BUF_N")
		)
	)
	(footprint ""
		(layer "F.Cu")
		(at 367.812066 -419.29558 90)
		(property "Reference" "U270"
			(at -0.13208 -2.975864 90)
			(unlocked yes)
			(layer "F.SilkS")
			(effects
				(font
					(size 0.7874 0.5842)
					(thickness 0.1524)
				)
				(justify left)
			)
		)
		(property "Value" ""
			(at 0 0 90)
			(layer "F.Fab")
			(effects
				(font
					(size 1.27 1.27)
				)
			)
		)
		(duplicate_pad_numbers_are_jumpers no)
		(fp_line
			(start 3.447796 -2.500122)
			(end 1.484122 -2.500122)
			(stroke
				(width 0.1524)
				(type default)
			)
			(layer "F.SilkS")
		)
		(fp_line
			(start 1.484122 -2.500122)
			(end 0 -1.016)
			(stroke
				(width 0.1524)
				(type default)
			)
			(layer "F.SilkS")
		)
		(fp_line
			(start -1.484122 -2.500122)
			(end -3.447796 -2.500122)
			(stroke
				(width 0.1524)
				(type default)
			)
			(layer "F.SilkS")
		)
		(fp_line
			(start -3.447796 -2.500122)
			(end -3.447796 2.500122)
			(stroke
				(width 0.1524)
				(type default)
			)
			(layer "F.SilkS")
		)
		(fp_line
			(start 0 -1.016)
			(end -1.484122 -2.500122)
			(stroke
				(width 0.1524)
				(type default)
			)
			(layer "F.SilkS")
		)
		(fp_line
			(start 3.447796 2.500122)
			(end 3.447796 -2.500122)
			(stroke
				(width 0.1524)
				(type default)
			)
			(layer "F.SilkS")
		)
		(fp_line
			(start -3.447796 2.500122)
			(end 3.447796 2.500122)
			(stroke
				(width 0.1524)
				(type default)
			)
			(layer "F.SilkS")
		)
		(fp_poly
			(pts
				(xy -1.063244 -3.198876) (xy -0.561848 -2.775966) (xy -1.235456 -2.485898)
			)
			(stroke
				(width 0)
				(type default)
			)
			(fill yes)
			(layer "F.SilkS")
		)
		(fp_line
			(start 1.999996 -2.500122)
			(end -1.999996 -2.500122)
			(stroke
				(width 0.1)
				(type default)
			)
			(layer "F.Fab")
		)
		(fp_line
			(start -1.999996 -2.500122)
			(end -1.999996 2.500122)
			(stroke
				(width 0.1)
				(type default)
			)
			(layer "F.Fab")
		)
		(fp_line
			(start 1.999996 2.500122)
			(end 1.999996 -2.500122)
			(stroke
				(width 0.1)
				(type default)
			)
			(layer "F.Fab")
		)
		(fp_line
			(start -1.999996 2.500122)
			(end 1.999996 2.500122)
			(stroke
				(width 0.1)
				(type default)
			)
			(layer "F.Fab")
		)
		(fp_poly
			(pts
				(xy -4.5974 -2.413) (xy -4.5974 -1.397) (xy -3.5814 -1.905)
			)
			(stroke
				(width 0)
				(type default)
			)
			(fill yes)
			(layer "F.Fab")
		)
		(pad "1" smd rect
			(at -2.649982 -1.905)
			(size 0.6096 1.3208)
			(layers "F.Cu" "F.Mask" "F.Paste")
			(net "SMB_LM75_0_3V3AUX_SDA_R1")
		)
		(pad "2" smd rect
			(at -2.649982 -0.635)
			(size 0.6096 1.3208)
			(layers "F.Cu" "F.Mask" "F.Paste")
			(net "SMB_LM75_0_3V3AUX_SCL_R1")
		)
		(pad "3" smd rect
			(at -2.649982 0.635)
			(size 0.6096 1.3208)
			(layers "F.Cu" "F.Mask" "F.Paste")
			(net "FM_G751_0_ALERT_N")
		)
		(pad "4" smd rect
			(at -2.649982 1.905)
			(size 0.6096 1.3208)
			(layers "F.Cu" "F.Mask" "F.Paste")
			(net "GND")
		)
		(pad "5" smd rect
			(at 2.649982 1.905)
			(size 0.6096 1.3208)
			(layers "F.Cu" "F.Mask" "F.Paste")
			(net "U270_0_ADD2")
		)
		(pad "6" smd rect
			(at 2.649982 0.635)
			(size 0.6096 1.3208)
			(layers "F.Cu" "F.Mask" "F.Paste")
			(net "U270_0_ADD1")
		)
		(pad "7" smd rect
			(at 2.649982 -0.635)
			(size 0.6096 1.3208)
			(layers "F.Cu" "F.Mask" "F.Paste")
			(net "U270_0_ADD0")
		)
		(pad "8" smd rect
			(at 2.649982 -1.905)
			(size 0.6096 1.3208)
			(layers "F.Cu" "F.Mask" "F.Paste")
			(net "P3V3_AUX")
		)
	)
	(footprint ""
		(layer "F.Cu")
		(at 300.538388 -5.077206 180)
		(property "Reference" "J84"
			(at -4.342384 -1.077976 90)
			(unlocked yes)
			(layer "F.SilkS")
			(effects
				(font
					(size 0.7874 0.5842)
					(thickness 0.1524)
				)
				(justify left)
			)
		)
		(property "Value" ""
			(at 0 0 180)
			(layer "F.Fab")
			(effects
				(font
					(size 1.27 1.27)
				)
			)
		)
		(duplicate_pad_numbers_are_jumpers no)
		(fp_line
			(start 1.2192 2.06756)
			(end -1.2192 2.06756)
			(stroke
				(width 0.1524)
				(type default)
			)
			(layer "F.SilkS")
		)
		(fp_line
			(start 1.2192 -2.06756)
			(end 1.2192 2.06756)
			(stroke
				(width 0.1524)
				(type default)
			)
			(layer "F.SilkS")
		)
		(fp_line
			(start -1.2192 2.06756)
			(end -1.2192 -2.06756)
			(stroke
				(width 0.1524)
				(type default)
			)
			(layer "F.SilkS")
		)
		(fp_line
			(start -1.2192 -2.06756)
			(end 1.2192 -2.06756)
			(stroke
				(width 0.1524)
				(type default)
			)
			(layer "F.SilkS")
		)
		(pad "" np_thru_hole circle
			(at -2.8829 -1.27 90)
			(size 1.0414 1.0414)
			(drill 1.0414)
			(layers "*.Cu" "*.Mask")
			(clearance 0.381)
			(thermal_gap 0.381)
		)
		(pad "" np_thru_hole circle
			(at -2.8829 1.27 90)
			(size 1.0414 1.0414)
			(drill 1.0414)
			(layers "*.Cu" "*.Mask")
			(clearance 0.381)
			(thermal_gap 0.381)
		)
		(pad "" np_thru_hole circle
			(at 3.4671 -1.27 90)
			(size 1.0414 1.0414)
			(drill 1.0414)
			(layers "*.Cu" "*.Mask")
			(clearance 0.381)
			(thermal_gap 0.381)
		)
		(pad "" np_thru_hole circle
			(at 3.4671 1.27 90)
			(size 1.0414 1.0414)
			(drill 1.0414)
			(layers "*.Cu" "*.Mask")
			(clearance 0.381)
			(thermal_gap 0.381)
		)
		(pad "1" smd rect
			(at 0.8255 -0.249936 90)
			(size 0.3048 0.508)
			(layers "F.Cu" "F.Mask" "F.Paste")
			(net "DELTA_L_85_10INCH_IN2_DN")
		)
		(pad "2" smd rect
			(at 0.8255 0.249936 90)
			(size 0.3048 0.508)
			(layers "F.Cu" "F.Mask" "F.Paste")
			(net "DELTA_L_85_10INCH_IN2_DP")
		)
		(pad "3" smd circle
			(at 0 0 180)
			(size 0 0)
			(layers "F.Cu" "F.Mask" "F.Paste")
			(net "DELTA_L_GND_1")
		)
		(zone
			(layer "F.Cu")
			(hatch none 0.5)
			(connect_pads
				(clearance 0)
			)
			(min_thickness 0.25)
			(keepout
				(tracks not_allowed)
				(vias allowed)
				(pads allowed)
				(copperpour not_allowed)
				(footprints allowed)
			)
			(placement
				(enabled no)
				(sheetname "")
			)
			(fill
				(thermal_gap 0.5)
				(thermal_bridge_width 0.5)
				(island_removal_mode 0)
			)
			(polygon
				(pts
					(xy 299.420788 -4.528566) (xy 299.420788 -4.62407) (xy 300.017688 -4.62407) (xy 300.017688 -5.03047)
					(xy 299.420788 -5.03047) (xy 299.420788 -5.123942) (xy 300.017688 -5.123942) (xy 300.017688 -5.530342)
					(xy 299.420788 -5.530342) (xy 299.420788 -5.625846) (xy 300.119288 -5.625846) (xy 300.119288 -4.528566)
				)
			)
		)
		(zone
			(layers "F.Cu" "B.Cu" "In1.Cu" "In2.Cu" "In3.Cu" "In4.Cu" "In5.Cu" "In6.Cu"
				"In7.Cu" "In8.Cu" "In9.Cu" "In10.Cu" "In11.Cu" "In12.Cu" "In13.Cu" "In14.Cu"
				"In15.Cu" "In16.Cu"
			)
			(hatch none 0.5)
			(connect_pads
				(clearance 0)
			)
			(min_thickness 0.25)
			(keepout
				(tracks not_allowed)
				(vias allowed)
				(pads allowed)
				(copperpour not_allowed)
				(footprints allowed)
			)
			(placement
				(enabled no)
				(sheetname "")
			)
			(fill
				(thermal_gap 0.5)
				(thermal_bridge_width 0.5)
				(island_removal_mode 0)
			)
			(polygon
				(pts
					(arc
						(start 297.998388 -6.347206)
						(mid 296.144188 -6.347206)
						(end 297.998388 -6.347206)
					)
				)
			)
		)
		(zone
			(layers "F.Cu" "B.Cu" "In1.Cu" "In2.Cu" "In3.Cu" "In4.Cu" "In5.Cu" "In6.Cu"
				"In7.Cu" "In8.Cu" "In9.Cu" "In10.Cu" "In11.Cu" "In12.Cu" "In13.Cu" "In14.Cu"
				"In15.Cu" "In16.Cu"
			)
			(hatch none 0.5)
			(connect_pads
				(clearance 0)
			)
			(min_thickness 0.25)
			(keepout
				(tracks not_allowed)
				(vias allowed)
				(pads allowed)
				(copperpour not_allowed)
				(footprints allowed)
			)
			(placement
				(enabled no)
				(sheetname "")
			)
			(fill
				(thermal_gap 0.5)
				(thermal_bridge_width 0.5)
				(island_removal_mode 0)
			)
			(polygon
				(pts
					(arc
						(start 297.998388 -3.807206)
						(mid 296.144188 -3.807206)
						(end 297.998388 -3.807206)
					)
				)
			)
		)
		(zone
			(layers "F.Cu" "B.Cu" "In1.Cu" "In2.Cu" "In3.Cu" "In4.Cu" "In5.Cu" "In6.Cu"
				"In7.Cu" "In8.Cu" "In9.Cu" "In10.Cu" "In11.Cu" "In12.Cu" "In13.Cu" "In14.Cu"
				"In15.Cu" "In16.Cu"
			)
			(hatch none 0.5)
			(connect_pads
				(clearance 0)
			)
			(min_thickness 0.25)
			(keepout
				(tracks not_allowed)
				(vias allowed)
				(pads allowed)
				(copperpour not_allowed)
				(footprints allowed)
			)
			(placement
				(enabled no)
				(sheetname "")
			)
			(fill
				(thermal_gap 0.5)
				(thermal_bridge_width 0.5)
				(island_removal_mode 0)
			)
			(polygon
				(pts
					(arc
						(start 304.348388 -6.347206)
						(mid 302.494188 -6.347206)
						(end 304.348388 -6.347206)
					)
				)
			)
		)
		(zone
			(layers "F.Cu" "B.Cu" "In1.Cu" "In2.Cu" "In3.Cu" "In4.Cu" "In5.Cu" "In6.Cu"
				"In7.Cu" "In8.Cu" "In9.Cu" "In10.Cu" "In11.Cu" "In12.Cu" "In13.Cu" "In14.Cu"
				"In15.Cu" "In16.Cu"
			)
			(hatch none 0.5)
			(connect_pads
				(clearance 0)
			)
			(min_thickness 0.25)
			(keepout
				(tracks not_allowed)
				(vias allowed)
				(pads allowed)
				(copperpour not_allowed)
				(footprints allowed)
			)
			(placement
				(enabled no)
				(sheetname "")
			)
			(fill
				(thermal_gap 0.5)
				(thermal_bridge_width 0.5)
				(island_removal_mode 0)
			)
			(polygon
				(pts
					(arc
						(start 304.348388 -3.807206)
						(mid 302.494188 -3.807206)
						(end 304.348388 -3.807206)
					)
				)
			)
		)
	)
	(footprint ""
		(layer "F.Cu")
		(at 347.983048 -339.932772 -90)
		(property "Reference" "PC113_C1P0_6"
			(at 0 0 270)
			(layer "F.SilkS")
			(hide yes)
			(effects
				(font
					(size 1.27 1.27)
				)
			)
		)
		(property "Value" ""
			(at 0 0 270)
			(layer "F.Fab")
			(effects
				(font
					(size 1.27 1.27)
				)
			)
		)
		(duplicate_pad_numbers_are_jumpers no)
		(fp_line
			(start -0.7874 0.4064)
			(end -0.7874 -0.4064)
			(stroke
				(width 0.1524)
				(type default)
			)
			(layer "F.SilkS")
		)
		(fp_line
			(start 0.7874 0.4064)
			(end -0.7874 0.4064)
			(stroke
				(width 0.1524)
				(type default)
			)
			(layer "F.SilkS")
		)
		(fp_line
			(start -0.7874 -0.4064)
			(end 0.7874 -0.4064)
			(stroke
				(width 0.1524)
				(type default)
			)
			(layer "F.SilkS")
		)
		(fp_line
			(start 0.7874 -0.4064)
			(end 0.7874 0.4064)
			(stroke
				(width 0.1524)
				(type default)
			)
			(layer "F.SilkS")
		)
		(fp_line
			(start -0.67945 0.3048)
			(end -0.67945 -0.305054)
			(stroke
				(width 0.1)
				(type default)
			)
			(layer "F.Fab")
		)
		(fp_line
			(start -0.12065 0.3048)
			(end -0.67945 0.3048)
			(stroke
				(width 0.1)
				(type default)
			)
			(layer "F.Fab")
		)
		(fp_line
			(start 0.120396 0.3048)
			(end 0.120396 0.2794)
			(stroke
				(width 0.1)
				(type default)
			)
			(layer "F.Fab")
		)
		(fp_line
			(start 0.67945 0.3048)
			(end 0.120396 0.3048)
			(stroke
				(width 0.1)
				(type default)
			)
			(layer "F.Fab")
		)
		(fp_line
			(start -0.12065 0.2794)
			(end -0.12065 0.3048)
			(stroke
				(width 0.1)
				(type default)
			)
			(layer "F.Fab")
		)
		(fp_line
			(start 0.120396 0.2794)
			(end -0.12065 0.2794)
			(stroke
				(width 0.1)
				(type default)
			)
			(layer "F.Fab")
		)
		(fp_line
			(start -0.12065 -0.2794)
			(end 0.12065 -0.2794)
			(stroke
				(width 0.1)
				(type default)
			)
			(layer "F.Fab")
		)
		(fp_line
			(start 0.12065 -0.2794)
			(end 0.12065 -0.3048)
			(stroke
				(width 0.1)
				(type default)
			)
			(layer "F.Fab")
		)
		(fp_line
			(start 0.12065 -0.3048)
			(end 0.67945 -0.3048)
			(stroke
				(width 0.1)
				(type default)
			)
			(layer "F.Fab")
		)
		(fp_line
			(start 0.67945 -0.3048)
			(end 0.67945 0.3048)
			(stroke
				(width 0.1)
				(type default)
			)
			(layer "F.Fab")
		)
		(fp_line
			(start -0.67945 -0.305054)
			(end -0.12065 -0.305054)
			(stroke
				(width 0.1)
				(type default)
			)
			(layer "F.Fab")
		)
		(fp_line
			(start -0.12065 -0.305054)
			(end -0.12065 -0.2794)
			(stroke
				(width 0.1)
				(type default)
			)
			(layer "F.Fab")
		)
		(pad "1" smd circle
			(at -0.40005 0 270)
			(size 0 0)
			(layers "F.Cu" "F.Mask" "F.Paste")
			(net "PVDDCR_CPU1_P0_PVCC")
		)
		(pad "2" smd circle
			(at 0.40005 0 270)
			(size 0 0)
			(layers "F.Cu" "F.Mask" "F.Paste")
			(net "GND")
		)
	)
)
